(kicad_pcb
	(version 20260206)
	(generator "pcbnew")
	(generator_version "10.0")
	(general
		(thickness 1.6)
		(legacy_teardrops no)
	)
	(paper "A4")
	(title_block
		(title "03242023_DA0F0TMBIJ0_F0T_Motherboard_J_brd_V01_OCP.brd")
		(comment 1 "Grand Teton / footprints 3516-3522 of 6105")
	)
	(layers
		(0 "F.Cu" signal "TOP")
		(4 "In1.Cu" signal "GND")
		(6 "In2.Cu" signal "IN1")
		(8 "In3.Cu" signal "GND1")
		(10 "In4.Cu" signal "IN2")
		(12 "In5.Cu" signal "GND2")
		(14 "In6.Cu" signal "IN3")
		(16 "In7.Cu" signal "GND3")
		(18 "In8.Cu" signal "VCC")
		(20 "In9.Cu" signal "VCC1")
		(22 "In10.Cu" signal "GND4")
		(24 "In11.Cu" signal "IN4")
		(26 "In12.Cu" signal "GND5")
		(28 "In13.Cu" signal "IN5")
		(30 "In14.Cu" signal "GND6")
		(32 "In15.Cu" signal "IN6")
		(34 "In16.Cu" signal "GND7")
		(2 "B.Cu" signal "BOTTOM")
		(9 "F.Adhes" user "F.Adhesive")
		(11 "B.Adhes" user "B.Adhesive")
		(13 "F.Paste" user "Package Geometry/Pastemask Top")
		(15 "B.Paste" user "Package Geometry/Pastemask Bottom")
		(5 "F.SilkS" user "Ref Des/Silkscreen Top")
		(7 "B.SilkS" user "Ref Des/Silkscreen Bottom")
		(1 "F.Mask" user "Board Geometry/Soldermask Top")
		(3 "B.Mask" user "Board Geometry/Soldermask Bottom")
		(17 "Dwgs.User" user "User.Drawings")
		(19 "Cmts.User" user "User.Comments")
		(21 "Eco1.User" user "User.Eco1")
		(23 "Eco2.User" user "User.Eco2")
		(25 "Edge.Cuts" user "Board Geometry/Outline")
		(27 "Margin" user)
		(31 "F.CrtYd" user "Package Geometry/Place Bound Top")
		(29 "B.CrtYd" user "Package Geometry/Place Bound Bottom")
		(35 "F.Fab" user "Ref Des/Assembly Top")
		(33 "B.Fab" user "Ref Des/Assembly Bottom")
	)
	(footprint ""
		(layer "F.Cu")
		(at 335.933288 -408.517344 -90)
		(property "Reference" "C922"
			(at 0 0 270)
			(layer "F.SilkS")
			(hide yes)
			(effects
				(font
					(size 1.27 1.27)
				)
			)
		)
		(property "Value" ""
			(at 0 0 270)
			(layer "F.Fab")
			(effects
				(font
					(size 1.27 1.27)
				)
			)
		)
		(duplicate_pad_numbers_are_jumpers no)
		(fp_line
			(start -0.299974 0.150114)
			(end -0.299974 -0.150114)
			(stroke
				(width 0.1)
				(type default)
			)
			(layer "F.Fab")
		)
		(fp_line
			(start 0.299974 0.150114)
			(end -0.299974 0.150114)
			(stroke
				(width 0.1)
				(type default)
			)
			(layer "F.Fab")
		)
		(fp_line
			(start -0.299974 -0.150114)
			(end 0.299974 -0.150114)
			(stroke
				(width 0.1)
				(type default)
			)
			(layer "F.Fab")
		)
		(fp_line
			(start 0.299974 -0.150114)
			(end 0.299974 0.150114)
			(stroke
				(width 0.1)
				(type default)
			)
			(layer "F.Fab")
		)
		(pad "1" smd rect
			(at -0.2667 0 270)
			(size 0.3048 0.381)
			(layers "F.Cu" "F.Mask" "F.Paste")
			(net "P5E_CPU0_PE0_TX_C_DN<5>")
		)
		(pad "2" smd rect
			(at 0.2667 0 270)
			(size 0.3048 0.381)
			(layers "F.Cu" "F.Mask" "F.Paste")
			(net "P5E_CPU0_PE0_TX_DN<5>")
		)
	)
	(footprint ""
		(layer "F.Cu")
		(at 352.163888 -408.517344 -90)
		(property "Reference" "C933"
			(at 0 0 270)
			(layer "F.SilkS")
			(hide yes)
			(effects
				(font
					(size 1.27 1.27)
				)
			)
		)
		(property "Value" ""
			(at 0 0 270)
			(layer "F.Fab")
			(effects
				(font
					(size 1.27 1.27)
				)
			)
		)
		(duplicate_pad_numbers_are_jumpers no)
		(fp_line
			(start -0.299974 0.150114)
			(end -0.299974 -0.150114)
			(stroke
				(width 0.1)
				(type default)
			)
			(layer "F.Fab")
		)
		(fp_line
			(start 0.299974 0.150114)
			(end -0.299974 0.150114)
			(stroke
				(width 0.1)
				(type default)
			)
			(layer "F.Fab")
		)
		(fp_line
			(start -0.299974 -0.150114)
			(end 0.299974 -0.150114)
			(stroke
				(width 0.1)
				(type default)
			)
			(layer "F.Fab")
		)
		(fp_line
			(start 0.299974 -0.150114)
			(end 0.299974 0.150114)
			(stroke
				(width 0.1)
				(type default)
			)
			(layer "F.Fab")
		)
		(pad "1" smd rect
			(at -0.2667 0 270)
			(size 0.3048 0.381)
			(layers "F.Cu" "F.Mask" "F.Paste")
			(net "P5E_CPU0_PE0_TX_C_DP<0>")
		)
		(pad "2" smd rect
			(at 0.2667 0 270)
			(size 0.3048 0.381)
			(layers "F.Cu" "F.Mask" "F.Paste")
			(net "P5E_CPU0_PE0_TX_DP<0>")
		)
	)
	(footprint ""
		(layer "F.Cu")
		(at 181.15788 -97.119948 90)
		(property "Reference" "R219"
			(at 0 0 90)
			(layer "F.SilkS")
			(hide yes)
			(effects
				(font
					(size 1.27 1.27)
				)
			)
		)
		(property "Value" ""
			(at 0 0 90)
			(layer "F.Fab")
			(effects
				(font
					(size 1.27 1.27)
				)
			)
		)
		(duplicate_pad_numbers_are_jumpers no)
		(fp_line
			(start 0.7874 -0.4064)
			(end 0.7874 0.4064)
			(stroke
				(width 0.1524)
				(type default)
			)
			(layer "F.SilkS")
		)
		(fp_line
			(start -0.7874 -0.4064)
			(end 0.7874 -0.4064)
			(stroke
				(width 0.1524)
				(type default)
			)
			(layer "F.SilkS")
		)
		(fp_line
			(start 0.7874 0.4064)
			(end -0.7874 0.4064)
			(stroke
				(width 0.1524)
				(type default)
			)
			(layer "F.SilkS")
		)
		(fp_line
			(start -0.7874 0.4064)
			(end -0.7874 -0.4064)
			(stroke
				(width 0.1524)
				(type default)
			)
			(layer "F.SilkS")
		)
		(fp_line
			(start -0.12065 -0.305054)
			(end -0.12065 -0.2794)
			(stroke
				(width 0.1)
				(type default)
			)
			(layer "F.Fab")
		)
		(fp_line
			(start -0.67945 -0.305054)
			(end -0.12065 -0.305054)
			(stroke
				(width 0.1)
				(type default)
			)
			(layer "F.Fab")
		)
		(fp_line
			(start 0.67945 -0.3048)
			(end 0.67945 0.3048)
			(stroke
				(width 0.1)
				(type default)
			)
			(layer "F.Fab")
		)
		(fp_line
			(start 0.12065 -0.3048)
			(end 0.67945 -0.3048)
			(stroke
				(width 0.1)
				(type default)
			)
			(layer "F.Fab")
		)
		(fp_line
			(start 0.12065 -0.2794)
			(end 0.12065 -0.3048)
			(stroke
				(width 0.1)
				(type default)
			)
			(layer "F.Fab")
		)
		(fp_line
			(start -0.12065 -0.2794)
			(end 0.12065 -0.2794)
			(stroke
				(width 0.1)
				(type default)
			)
			(layer "F.Fab")
		)
		(fp_line
			(start 0.120396 0.2794)
			(end -0.12065 0.2794)
			(stroke
				(width 0.1)
				(type default)
			)
			(layer "F.Fab")
		)
		(fp_line
			(start -0.12065 0.2794)
			(end -0.12065 0.3048)
			(stroke
				(width 0.1)
				(type default)
			)
			(layer "F.Fab")
		)
		(fp_line
			(start 0.67945 0.3048)
			(end 0.120396 0.3048)
			(stroke
				(width 0.1)
				(type default)
			)
			(layer "F.Fab")
		)
		(fp_line
			(start 0.120396 0.3048)
			(end 0.120396 0.2794)
			(stroke
				(width 0.1)
				(type default)
			)
			(layer "F.Fab")
		)
		(fp_line
			(start -0.12065 0.3048)
			(end -0.67945 0.3048)
			(stroke
				(width 0.1)
				(type default)
			)
			(layer "F.Fab")
		)
		(fp_line
			(start -0.67945 0.3048)
			(end -0.67945 -0.305054)
			(stroke
				(width 0.1)
				(type default)
			)
			(layer "F.Fab")
		)
		(pad "1" smd circle
			(at -0.40005 0 90)
			(size 0 0)
			(layers "F.Cu" "F.Mask" "F.Paste")
			(net "PVNN_TERM_CPU0")
		)
		(pad "2" smd circle
			(at 0.40005 0 90)
			(size 0 0)
			(layers "F.Cu" "F.Mask" "F.Paste")
			(net "H_CPU0_MEMHOT_IN_LVC1_R1_N")
		)
	)
	(footprint ""
		(layer "F.Cu")
		(at 77.107542 -345.402662 90)
		(property "Reference" "PC480"
			(at 0 0 90)
			(layer "F.SilkS")
			(hide yes)
			(effects
				(font
					(size 1.27 1.27)
				)
			)
		)
		(property "Value" ""
			(at 0 0 90)
			(layer "F.Fab")
			(effects
				(font
					(size 1.27 1.27)
				)
			)
		)
		(duplicate_pad_numbers_are_jumpers no)
		(fp_line
			(start 0.7874 -0.4064)
			(end 0.7874 0.4064)
			(stroke
				(width 0.1524)
				(type default)
			)
			(layer "F.SilkS")
		)
		(fp_line
			(start -0.7874 -0.4064)
			(end 0.7874 -0.4064)
			(stroke
				(width 0.1524)
				(type default)
			)
			(layer "F.SilkS")
		)
		(fp_line
			(start 0.7874 0.4064)
			(end -0.7874 0.4064)
			(stroke
				(width 0.1524)
				(type default)
			)
			(layer "F.SilkS")
		)
		(fp_line
			(start -0.7874 0.4064)
			(end -0.7874 -0.4064)
			(stroke
				(width 0.1524)
				(type default)
			)
			(layer "F.SilkS")
		)
		(fp_line
			(start -0.12065 -0.305054)
			(end -0.12065 -0.2794)
			(stroke
				(width 0.1)
				(type default)
			)
			(layer "F.Fab")
		)
		(fp_line
			(start -0.67945 -0.305054)
			(end -0.12065 -0.305054)
			(stroke
				(width 0.1)
				(type default)
			)
			(layer "F.Fab")
		)
		(fp_line
			(start 0.67945 -0.3048)
			(end 0.67945 0.3048)
			(stroke
				(width 0.1)
				(type default)
			)
			(layer "F.Fab")
		)
		(fp_line
			(start 0.12065 -0.3048)
			(end 0.67945 -0.3048)
			(stroke
				(width 0.1)
				(type default)
			)
			(layer "F.Fab")
		)
		(fp_line
			(start 0.12065 -0.2794)
			(end 0.12065 -0.3048)
			(stroke
				(width 0.1)
				(type default)
			)
			(layer "F.Fab")
		)
		(fp_line
			(start -0.12065 -0.2794)
			(end 0.12065 -0.2794)
			(stroke
				(width 0.1)
				(type default)
			)
			(layer "F.Fab")
		)
		(fp_line
			(start 0.120396 0.2794)
			(end -0.12065 0.2794)
			(stroke
				(width 0.1)
				(type default)
			)
			(layer "F.Fab")
		)
		(fp_line
			(start -0.12065 0.2794)
			(end -0.12065 0.3048)
			(stroke
				(width 0.1)
				(type default)
			)
			(layer "F.Fab")
		)
		(fp_line
			(start 0.67945 0.3048)
			(end 0.120396 0.3048)
			(stroke
				(width 0.1)
				(type default)
			)
			(layer "F.Fab")
		)
		(fp_line
			(start 0.120396 0.3048)
			(end 0.120396 0.2794)
			(stroke
				(width 0.1)
				(type default)
			)
			(layer "F.Fab")
		)
		(fp_line
			(start -0.12065 0.3048)
			(end -0.67945 0.3048)
			(stroke
				(width 0.1)
				(type default)
			)
			(layer "F.Fab")
		)
		(fp_line
			(start -0.67945 0.3048)
			(end -0.67945 -0.305054)
			(stroke
				(width 0.1)
				(type default)
			)
			(layer "F.Fab")
		)
		(pad "1" smd circle
			(at -0.40005 0 90)
			(size 0 0)
			(layers "F.Cu" "F.Mask" "F.Paste")
			(net "PVCCIN_CPU1_VDD7")
		)
		(pad "2" smd circle
			(at 0.40005 0 90)
			(size 0 0)
			(layers "F.Cu" "F.Mask" "F.Paste")
			(net "GND")
		)
	)
	(footprint ""
		(layer "F.Cu")
		(at 112.799876 -79.078836)
		(property "Reference" "D97"
			(at -55.73141 38.649402 90)
			(unlocked yes)
			(layer "F.SilkS")
			(effects
				(font
					(size 0.635 0.4064)
					(thickness 0.1524)
				)
				(justify left)
			)
		)
		(property "Value" ""
			(at 0 0 0)
			(layer "F.Fab")
			(effects
				(font
					(size 1.27 1.27)
				)
			)
		)
		(duplicate_pad_numbers_are_jumpers no)
		(fp_line
			(start -0.90678 0.4826)
			(end -0.90678 -0.4699)
			(stroke
				(width 0.1524)
				(type default)
			)
			(layer "F.SilkS")
		)
		(fp_line
			(start -0.89408 -0.4826)
			(end 0.90678 -0.4826)
			(stroke
				(width 0.1524)
				(type default)
			)
			(layer "F.SilkS")
		)
		(fp_line
			(start -0.79248 -0.4826)
			(end 1.03378 -0.4826)
			(stroke
				(width 0.1524)
				(type default)
			)
			(layer "F.SilkS")
		)
		(fp_line
			(start -0.64008 -0.4826)
			(end 1.16078 -0.4826)
			(stroke
				(width 0.1524)
				(type default)
			)
			(layer "F.SilkS")
		)
		(fp_line
			(start 0.90678 -0.4826)
			(end 0.90678 0.4826)
			(stroke
				(width 0.1524)
				(type default)
			)
			(layer "F.SilkS")
		)
		(fp_line
			(start 0.90678 0.4826)
			(end -0.90678 0.4826)
			(stroke
				(width 0.1524)
				(type default)
			)
			(layer "F.SilkS")
		)
		(fp_line
			(start 1.03378 -0.4826)
			(end 1.03378 0.4826)
			(stroke
				(width 0.1524)
				(type default)
			)
			(layer "F.SilkS")
		)
		(fp_line
			(start 1.03378 0.4826)
			(end -0.79248 0.4826)
			(stroke
				(width 0.1524)
				(type default)
			)
			(layer "F.SilkS")
		)
		(fp_line
			(start 1.16078 -0.4826)
			(end 1.16078 0.4826)
			(stroke
				(width 0.1524)
				(type default)
			)
			(layer "F.SilkS")
		)
		(fp_line
			(start 1.16078 0.4826)
			(end -0.64008 0.4826)
			(stroke
				(width 0.1524)
				(type default)
			)
			(layer "F.SilkS")
		)
		(fp_line
			(start -0.499872 -0.249936)
			(end 0.499872 -0.249936)
			(stroke
				(width 0.1)
				(type default)
			)
			(layer "F.Fab")
		)
		(fp_line
			(start -0.499872 0.249936)
			(end -0.499872 -0.249936)
			(stroke
				(width 0.1)
				(type default)
			)
			(layer "F.Fab")
		)
		(fp_line
			(start 0.499872 -0.249936)
			(end 0.499872 0.249936)
			(stroke
				(width 0.1)
				(type default)
			)
			(layer "F.Fab")
		)
		(fp_line
			(start 0.499872 0.249936)
			(end -0.499872 0.249936)
			(stroke
				(width 0.1)
				(type default)
			)
			(layer "F.Fab")
		)
		(pad "A" smd rect
			(at -0.47498 0)
			(size 0.6096 0.7112)
			(layers "F.Cu" "F.Mask" "F.Paste")
			(net "LED_P5V_AUX")
		)
		(pad "C" smd rect
			(at 0.47498 0)
			(size 0.6096 0.7112)
			(layers "F.Cu" "F.Mask" "F.Paste")
			(net "GND")
		)
	)
	(footprint ""
		(layer "F.Cu")
		(at 298.036996 -43.594274 90)
		(property "Reference" "R1343"
			(at 0 0 90)
			(layer "F.SilkS")
			(hide yes)
			(effects
				(font
					(size 1.27 1.27)
				)
			)
		)
		(property "Value" ""
			(at 0 0 90)
			(layer "F.Fab")
			(effects
				(font
					(size 1.27 1.27)
				)
			)
		)
		(duplicate_pad_numbers_are_jumpers no)
		(fp_line
			(start 0.7874 -0.4064)
			(end 0.7874 0.4064)
			(stroke
				(width 0.1524)
				(type default)
			)
			(layer "F.SilkS")
		)
		(fp_line
			(start -0.7874 -0.4064)
			(end 0.7874 -0.4064)
			(stroke
				(width 0.1524)
				(type default)
			)
			(layer "F.SilkS")
		)
		(fp_line
			(start 0.7874 0.4064)
			(end -0.7874 0.4064)
			(stroke
				(width 0.1524)
				(type default)
			)
			(layer "F.SilkS")
		)
		(fp_line
			(start -0.7874 0.4064)
			(end -0.7874 -0.4064)
			(stroke
				(width 0.1524)
				(type default)
			)
			(layer "F.SilkS")
		)
		(fp_line
			(start -0.12065 -0.305054)
			(end -0.12065 -0.2794)
			(stroke
				(width 0.1)
				(type default)
			)
			(layer "F.Fab")
		)
		(fp_line
			(start -0.67945 -0.305054)
			(end -0.12065 -0.305054)
			(stroke
				(width 0.1)
				(type default)
			)
			(layer "F.Fab")
		)
		(fp_line
			(start 0.67945 -0.3048)
			(end 0.67945 0.3048)
			(stroke
				(width 0.1)
				(type default)
			)
			(layer "F.Fab")
		)
		(fp_line
			(start 0.12065 -0.3048)
			(end 0.67945 -0.3048)
			(stroke
				(width 0.1)
				(type default)
			)
			(layer "F.Fab")
		)
		(fp_line
			(start 0.12065 -0.2794)
			(end 0.12065 -0.3048)
			(stroke
				(width 0.1)
				(type default)
			)
			(layer "F.Fab")
		)
		(fp_line
			(start -0.12065 -0.2794)
			(end 0.12065 -0.2794)
			(stroke
				(width 0.1)
				(type default)
			)
			(layer "F.Fab")
		)
		(fp_line
			(start 0.120396 0.2794)
			(end -0.12065 0.2794)
			(stroke
				(width 0.1)
				(type default)
			)
			(layer "F.Fab")
		)
		(fp_line
			(start -0.12065 0.2794)
			(end -0.12065 0.3048)
			(stroke
				(width 0.1)
				(type default)
			)
			(layer "F.Fab")
		)
		(fp_line
			(start 0.67945 0.3048)
			(end 0.120396 0.3048)
			(stroke
				(width 0.1)
				(type default)
			)
			(layer "F.Fab")
		)
		(fp_line
			(start 0.120396 0.3048)
			(end 0.120396 0.2794)
			(stroke
				(width 0.1)
				(type default)
			)
			(layer "F.Fab")
		)
		(fp_line
			(start -0.12065 0.3048)
			(end -0.67945 0.3048)
			(stroke
				(width 0.1)
				(type default)
			)
			(layer "F.Fab")
		)
		(fp_line
			(start -0.67945 0.3048)
			(end -0.67945 -0.305054)
			(stroke
				(width 0.1)
				(type default)
			)
			(layer "F.Fab")
		)
		(pad "1" smd circle
			(at -0.40005 0 90)
			(size 0 0)
			(layers "F.Cu" "F.Mask" "F.Paste")
			(net "P1V05_PCH_AUX")
		)
		(pad "2" smd circle
			(at 0.40005 0 90)
			(size 0 0)
			(layers "F.Cu" "F.Mask" "F.Paste")
			(net "FM_PASSWORD_CLEAR_N")
		)
	)
	(footprint ""
		(layer "F.Cu")
		(at 37.890196 -122.380502 -90)
		(property "Reference" "R1793"
			(at 0 0 270)
			(layer "F.SilkS")
			(hide yes)
			(effects
				(font
					(size 1.27 1.27)
				)
			)
		)
		(property "Value" ""
			(at 0 0 270)
			(layer "F.Fab")
			(effects
				(font
					(size 1.27 1.27)
				)
			)
		)
		(duplicate_pad_numbers_are_jumpers no)
		(fp_line
			(start -0.7874 0.4064)
			(end -0.7874 -0.4064)
			(stroke
				(width 0.1524)
				(type default)
			)
			(layer "F.SilkS")
		)
		(fp_line
			(start 0.7874 0.4064)
			(end -0.7874 0.4064)
			(stroke
				(width 0.1524)
				(type default)
			)
			(layer "F.SilkS")
		)
		(fp_line
			(start -0.7874 -0.4064)
			(end 0.7874 -0.4064)
			(stroke
				(width 0.1524)
				(type default)
			)
			(layer "F.SilkS")
		)
		(fp_line
			(start 0.7874 -0.4064)
			(end 0.7874 0.4064)
			(stroke
				(width 0.1524)
				(type default)
			)
			(layer "F.SilkS")
		)
		(fp_line
			(start -0.67945 0.3048)
			(end -0.67945 -0.305054)
			(stroke
				(width 0.1)
				(type default)
			)
			(layer "F.Fab")
		)
		(fp_line
			(start -0.12065 0.3048)
			(end -0.67945 0.3048)
			(stroke
				(width 0.1)
				(type default)
			)
			(layer "F.Fab")
		)
		(fp_line
			(start 0.120396 0.3048)
			(end 0.120396 0.2794)
			(stroke
				(width 0.1)
				(type default)
			)
			(layer "F.Fab")
		)
		(fp_line
			(start 0.67945 0.3048)
			(end 0.120396 0.3048)
			(stroke
				(width 0.1)
				(type default)
			)
			(layer "F.Fab")
		)
		(fp_line
			(start -0.12065 0.2794)
			(end -0.12065 0.3048)
			(stroke
				(width 0.1)
				(type default)
			)
			(layer "F.Fab")
		)
		(fp_line
			(start 0.120396 0.2794)
			(end -0.12065 0.2794)
			(stroke
				(width 0.1)
				(type default)
			)
			(layer "F.Fab")
		)
		(fp_line
			(start -0.12065 -0.2794)
			(end 0.12065 -0.2794)
			(stroke
				(width 0.1)
				(type default)
			)
			(layer "F.Fab")
		)
		(fp_line
			(start 0.12065 -0.2794)
			(end 0.12065 -0.3048)
			(stroke
				(width 0.1)
				(type default)
			)
			(layer "F.Fab")
		)
		(fp_line
			(start 0.12065 -0.3048)
			(end 0.67945 -0.3048)
			(stroke
				(width 0.1)
				(type default)
			)
			(layer "F.Fab")
		)
		(fp_line
			(start 0.67945 -0.3048)
			(end 0.67945 0.3048)
			(stroke
				(width 0.1)
				(type default)
			)
			(layer "F.Fab")
		)
		(fp_line
			(start -0.67945 -0.305054)
			(end -0.12065 -0.305054)
			(stroke
				(width 0.1)
				(type default)
			)
			(layer "F.Fab")
		)
		(fp_line
			(start -0.12065 -0.305054)
			(end -0.12065 -0.2794)
			(stroke
				(width 0.1)
				(type default)
			)
			(layer "F.Fab")
		)
		(pad "1" smd circle
			(at -0.40005 0 270)
			(size 0 0)
			(layers "F.Cu" "F.Mask" "F.Paste")
			(net "SMB_VR_3V3AUX_SCL_R1")
		)
		(pad "2" smd circle
			(at 0.40005 0 270)
			(size 0 0)
			(layers "F.Cu" "F.Mask" "F.Paste")
			(net "SMB_SEN_MAM_3V3AUX_SCL")
		)
	)
)
